# TIMECARD (Time Appliance Project (Time Card)) — schematic netlist excerpt (pin names and nets, part order shuffled) for the footprints in the layout excerpt that follows; sources: Cadence DE-HDL packaged netlist, KiCad conversion of R4006-B0001-02_R01.brd

C138  CAPACITOR  4.7UF 6.3V 20%  pkg SMC_0402R_H026  page 14 : \1\ = XP1R8V_FPGA_VCCAUX ; \2\ = SG
C201  CAPACITOR  0.1UF 10V 10%  pkg SMC_0402R_H022  page 14 : \1\ = XP1R0V_FPGA_VCCINT ; \2\ = SG

(kicad_pcb
	(version 20260206)
	(generator "pcbnew")
	(generator_version "10.0")
	(general
		(thickness 1.6)
		(legacy_teardrops no)
	)
	(paper "A4")
	(title_block
		(title "timecard-production-celestica-r4006 — R4006-B0001-02_R01.brd")
		(comment 1 "Time Appliance Project (Time Card) / footprints 1110-1111 of 1113")
	)
	(layers
		(0 "F.Cu" signal "TOP")
		(4 "In1.Cu" signal "L02_GND1")
		(6 "In2.Cu" signal "L03_SIG1")
		(8 "In3.Cu" signal "L04_GND2")
		(10 "In4.Cu" signal "L05_VCC1")
		(12 "In5.Cu" signal "L06_VCC2")
		(14 "In6.Cu" signal "L07_GND3")
		(16 "In7.Cu" signal "L08_SIG2")
		(18 "In8.Cu" signal "L09_GND4")
		(2 "B.Cu" signal "BOTTOM")
		(9 "F.Adhes" user "F.Adhesive")
		(11 "B.Adhes" user "B.Adhesive")
		(13 "F.Paste" user "Package Geometry/Pastemask Top")
		(15 "B.Paste" user "Package Geometry/Pastemask Bottom")
		(5 "F.SilkS" user "Ref Des/Silkscreen Top")
		(7 "B.SilkS" user "Ref Des/Silkscreen Bottom")
		(1 "F.Mask" user "Board Geometry/Soldermask Top")
		(3 "B.Mask" user "Board Geometry/Soldermask Bottom")
		(17 "Dwgs.User" user "User.Drawings")
		(19 "Cmts.User" user "User.Comments")
		(21 "Eco1.User" user "User.Eco1")
		(23 "Eco2.User" user "User.Eco2")
		(25 "Edge.Cuts" user "Board Geometry/Outline")
		(27 "Margin" user)
		(31 "F.CrtYd" user "Package Geometry/Place Bound Top")
		(29 "B.CrtYd" user "Package Geometry/Place Bound Bottom")
		(35 "F.Fab" user "Ref Des/Assembly Top")
		(33 "B.Fab" user "Ref Des/Assembly Bottom")
	)
	(footprint ""
		(layer "B.Cu")
		(at 111.847122 -42.323004 90)
		(property "Reference" "C201"
			(at -1.141984 -42.018712 270)
			(unlocked yes)
			(layer "B.SilkS")
			(effects
				(font
					(size 0.635 0.4064)
					(thickness 0.1524)
				)
				(justify mirror)
			)
		)
		(property "Value" "VAL*"
			(at 0 3.718306 90)
			(unlocked yes)
			(layer "B.Fab")
			(hide yes)
			(effects
				(font
					(size 0.7874 0.5842)
					(thickness 0.127)
				)
				(justify mirror)
			)
		)
		(property "Device Type" "CAPACITOR-G105-0B104-CK,0.1UF,A"
			(at 0 1.432306 90)
			(unlocked yes)
			(layer "B.Fab")
			(hide yes)
			(effects
				(font
					(size 0.7874 0.5842)
					(thickness 0.127)
				)
				(justify mirror)
			)
		)
		(property "User Part Number" "PARTNUM*"
			(at 0 2.575306 90)
			(unlocked yes)
			(layer "Cmts.User")
			(hide yes)
			(effects
				(font
					(size 0.7874 0.5842)
					(thickness 0.127)
				)
				(justify mirror)
			)
		)
		(property "Tolerance" "TOL*"
			(at 0 4.861306 90)
			(unlocked yes)
			(layer "Cmts.User")
			(hide yes)
			(effects
				(font
					(size 0.7874 0.5842)
					(thickness 0.127)
				)
				(justify mirror)
			)
		)
		(duplicate_pad_numbers_are_jumpers no)
		(fp_line
			(start 0.970026 -0.4699)
			(end -0.970026 -0.4699)
			(stroke
				(width 0.1)
				(type default)
			)
			(layer "B.SilkS")
		)
		(fp_line
			(start -0.970026 -0.4699)
			(end -0.970026 0.4699)
			(stroke
				(width 0.1)
				(type default)
			)
			(layer "B.SilkS")
		)
		(fp_line
			(start 0.970026 0.4699)
			(end 0.970026 -0.4699)
			(stroke
				(width 0.1)
				(type default)
			)
			(layer "B.SilkS")
		)
		(fp_line
			(start -0.970026 0.4699)
			(end 0.970026 0.4699)
			(stroke
				(width 0.1)
				(type default)
			)
			(layer "B.SilkS")
		)
		(fp_poly
			(pts
				(xy 0.970026 0.4699) (xy -0.970026 0.4699) (xy -0.970026 -0.4699) (xy 0.970026 -0.4699)
			)
			(stroke
				(width 0)
				(type default)
			)
			(fill no)
			(layer "B.CrtYd")
		)
		(fp_line
			(start 0.508 -0.3048)
			(end -0.508 -0.3048)
			(stroke
				(width 0.1)
				(type default)
			)
			(layer "B.Fab")
		)
		(fp_line
			(start -0.508 -0.3048)
			(end -0.508 0.3048)
			(stroke
				(width 0.1)
				(type default)
			)
			(layer "B.Fab")
		)
		(fp_line
			(start 0.508 0.3048)
			(end 0.508 -0.3048)
			(stroke
				(width 0.1)
				(type default)
			)
			(layer "B.Fab")
		)
		(fp_line
			(start -0.508 0.3048)
			(end 0.508 0.3048)
			(stroke
				(width 0.1)
				(type default)
			)
			(layer "B.Fab")
		)
		(pad "1" smd circle
			(at 0.500126 0 270)
			(size 0.635 0.635)
			(layers "B.Cu" "B.Mask" "B.Paste")
			(net "XP1R0V_FPGA_VCCINT")
		)
		(pad "2" smd circle
			(at -0.500126 0 270)
			(size 0.635 0.635)
			(layers "B.Cu" "B.Mask" "B.Paste")
			(net "SG")
		)
	)
	(footprint ""
		(layer "B.Cu")
		(at 113.347246 -42.82313 180)
		(property "Reference" "C138"
			(at 41.909746 -1.24968 0)
			(unlocked yes)
			(layer "B.SilkS")
			(effects
				(font
					(size 0.635 0.4064)
					(thickness 0.1524)
				)
				(justify mirror)
			)
		)
		(property "Value" "VAL*"
			(at 0 3.718306 180)
			(unlocked yes)
			(layer "B.Fab")
			(hide yes)
			(effects
				(font
					(size 0.7874 0.5842)
					(thickness 0.127)
				)
				(justify mirror)
			)
		)
		(property "Tolerance" "TOL*"
			(at 0 4.861306 180)
			(unlocked yes)
			(layer "Cmts.User")
			(hide yes)
			(effects
				(font
					(size 0.7874 0.5842)
					(thickness 0.127)
				)
				(justify mirror)
			)
		)
		(property "User Part Number" "PARTNUM*"
			(at 0 2.575306 180)
			(unlocked yes)
			(layer "Cmts.User")
			(hide yes)
			(effects
				(font
					(size 0.7874 0.5842)
					(thickness 0.127)
				)
				(justify mirror)
			)
		)
		(property "Device Type" "CAPACITOR-G105-0F475-BM,4.7UF,A"
			(at 0 1.432306 180)
			(unlocked yes)
			(layer "B.Fab")
			(hide yes)
			(effects
				(font
					(size 0.7874 0.5842)
					(thickness 0.127)
				)
				(justify mirror)
			)
		)
		(duplicate_pad_numbers_are_jumpers no)
		(fp_line
			(start 0.970026 0.4699)
			(end 0.970026 -0.4699)
			(stroke
				(width 0.1)
				(type default)
			)
			(layer "B.SilkS")
		)
		(fp_line
			(start 0.970026 -0.4699)
			(end -0.970026 -0.4699)
			(stroke
				(width 0.1)
				(type default)
			)
			(layer "B.SilkS")
		)
		(fp_line
			(start -0.970026 0.4699)
			(end 0.970026 0.4699)
			(stroke
				(width 0.1)
				(type default)
			)
			(layer "B.SilkS")
		)
		(fp_line
			(start -0.970026 -0.4699)
			(end -0.970026 0.4699)
			(stroke
				(width 0.1)
				(type default)
			)
			(layer "B.SilkS")
		)
		(fp_poly
			(pts
				(xy 0.970026 0.4699) (xy -0.970026 0.4699) (xy -0.970026 -0.4699) (xy 0.970026 -0.4699)
			)
			(stroke
				(width 0)
				(type default)
			)
			(fill no)
			(layer "B.CrtYd")
		)
		(fp_line
			(start 0.508 0.3048)
			(end 0.508 -0.3048)
			(stroke
				(width 0.1)
				(type default)
			)
			(layer "B.Fab")
		)
		(fp_line
			(start 0.508 -0.3048)
			(end -0.508 -0.3048)
			(stroke
				(width 0.1)
				(type default)
			)
			(layer "B.Fab")
		)
		(fp_line
			(start -0.508 0.3048)
			(end 0.508 0.3048)
			(stroke
				(width 0.1)
				(type default)
			)
			(layer "B.Fab")
		)
		(fp_line
			(start -0.508 -0.3048)
			(end -0.508 0.3048)
			(stroke
				(width 0.1)
				(type default)
			)
			(layer "B.Fab")
		)
		(pad "1" smd circle
			(at 0.500126 0)
			(size 0.635 0.635)
			(layers "B.Cu" "B.Mask" "B.Paste")
			(net "XP1R8V_FPGA_VCCAUX")
		)
		(pad "2" smd circle
			(at -0.500126 0)
			(size 0.635 0.635)
			(layers "B.Cu" "B.Mask" "B.Paste")
			(net "SG")
		)
	)
)
